(kicad_pcb
	(version 20241229)
	(generator "pcbnew")
	(generator_version "9.0")
	(general
		(thickness 1.6)
		(legacy_teardrops no)
	)
	(paper "A4")
	(title_block
		(title "OCuLink to PCIe adapter")
		(date "2025-06-18")
		(rev "1.0.0")
		(company "Antmicro Ltd")
		(comment 1 "www.antmicro.com")
		(comment 9 "footprints 129-132 of 159")
	)
	(layers
		(0 "F.Cu" signal)
		(4 "In1.Cu" signal)
		(6 "In2.Cu" signal)
		(2 "B.Cu" signal)
		(9 "F.Adhes" user "F.Adhesive")
		(11 "B.Adhes" user "B.Adhesive")
		(13 "F.Paste" user)
		(15 "B.Paste" user)
		(5 "F.SilkS" user "F.Silkscreen")
		(7 "B.SilkS" user "B.Silkscreen")
		(1 "F.Mask" user)
		(3 "B.Mask" user)
		(17 "Dwgs.User" user "User.Drawings")
		(19 "Cmts.User" user "User.Comments")
		(21 "Eco1.User" user "User.Eco1")
		(23 "Eco2.User" user "User.Eco2")
		(25 "Edge.Cuts" user)
		(27 "Margin" user)
		(31 "F.CrtYd" user "F.Courtyard")
		(29 "B.CrtYd" user "B.Courtyard")
		(35 "F.Fab" user)
		(33 "B.Fab" user)
	)
	(footprint "antmicro-footprints:SOD-123FL"
		(layer "F.Cu")
		(at 143 110.4)
		(property "Reference" "D7"
			(at -4 0.4 180)
			(layer "F.SilkS")
			(effects
				(font
					(size 0.7 0.7)
					(thickness 0.15)
				)
				(justify left bottom)
			)
		)
		(property "Value" "SZSMF4L14AT3G"
			(at 0 1.967 0)
			(layer "F.Fab")
			(effects
				(font
					(size 0.7 0.7)
					(thickness 0.15)
				)
				(justify left bottom)
			)
		)
		(property "Datasheet" "https://www.mouser.com/datasheet/2/240/media-3320461.pdf"
			(at 0 0 0)
			(layer "F.Fab")
			(hide yes)
			(effects
				(font
					(size 1.27 1.27)
					(thickness 0.15)
				)
			)
		)
		(property "Description" "ESD, TVS Diode, 14V, UNI, 400W, SOD-123FL"
			(at 0 0 0)
			(layer "F.Fab")
			(hide yes)
			(effects
				(font
					(size 1.27 1.27)
					(thickness 0.15)
				)
			)
		)
		(property "MPN" "SZSMF4L12AT3G"
			(at 0 0 0)
			(unlocked yes)
			(layer "F.Fab")
			(hide yes)
			(effects
				(font
					(size 1 1)
					(thickness 0.15)
				)
			)
		)
		(property "Author" "Antmicro"
			(at 0 0 0)
			(unlocked yes)
			(layer "F.Fab")
			(hide yes)
			(effects
				(font
					(size 1 1)
					(thickness 0.15)
				)
			)
		)
		(property "License" "Apache-2.0"
			(at 0 0 0)
			(unlocked yes)
			(layer "F.Fab")
			(hide yes)
			(effects
				(font
					(size 1 1)
					(thickness 0.15)
				)
			)
		)
		(property "Manufacturer" "Littelfuse"
			(at 0 0 0)
			(unlocked yes)
			(layer "F.Fab")
			(hide yes)
			(effects
				(font
					(size 1 1)
					(thickness 0.15)
				)
			)
		)
		(sheetname "/Power/")
		(sheetfile "power.kicad_sch")
		(attr smd)
		(fp_line
			(start -2.3 -1.1)
			(end -2.3 1.1)
			(stroke
				(width 0.15)
				(type solid)
			)
			(layer "F.SilkS")
		)
		(fp_line
			(start -2.3 1.1)
			(end 0 1.1)
			(stroke
				(width 0.15)
				(type solid)
			)
			(layer "F.SilkS")
		)
		(fp_line
			(start 0 -1.1)
			(end -2.3 -1.1)
			(stroke
				(width 0.15)
				(type solid)
			)
			(layer "F.SilkS")
		)
		(fp_rect
			(start -2.35 -1.125)
			(end 2.35 1.125)
			(stroke
				(width 0.05)
				(type solid)
			)
			(fill no)
			(layer "F.CrtYd")
		)
		(fp_rect
			(start -1.825 -0.875)
			(end 1.824 0.873)
			(stroke
				(width 0.15)
				(type solid)
			)
			(fill no)
			(layer "F.Fab")
		)
		(fp_rect
			(start -0.775 -0.875)
			(end -0.525 0.875)
			(stroke
				(width 0.15)
				(type solid)
			)
			(fill yes)
			(layer "F.Fab")
		)
		(fp_text user "License: Apache-2.0"
			(at -2.406 6.368 0)
			(layer "F.Fab")
			(effects
				(font
					(size 0.7 0.7)
					(thickness 0.15)
				)
				(justify left bottom)
			)
		)
		(fp_text user "Author: Antmicro"
			(at -2.406 5.168 0)
			(layer "F.Fab")
			(effects
				(font
					(size 0.7 0.7)
					(thickness 0.15)
				)
				(justify left bottom)
			)
		)
		(fp_text user "${REFERENCE}"
			(at 0 0 0)
			(layer "F.Fab")
			(effects
				(font
					(size 0.7 0.7)
					(thickness 0.15)
				)
				(justify left bottom)
			)
		)
		(pad "1" smd roundrect
			(at -1.43 0)
			(size 1.34 1.8)
			(layers "F.Cu" "F.Mask" "F.Paste")
			(roundrect_rratio 0.14)
			(net 118 "/Power/Ideal-diode-1/VIN")
			(pinfunction "C")
			(pintype "passive")
		)
		(pad "2" smd roundrect
			(at 1.429 0)
			(size 1.34 1.8)
			(layers "F.Cu" "F.Mask" "F.Paste")
			(roundrect_rratio 0.14)
			(net 66 "GND")
			(pinfunction "A")
			(pintype "passive")
		)
	)
	(footprint "antmicro-footprints:LED_0603_1608Metric_G"
		(layer "F.Cu")
		(at 151.5 157.17)
		(descr "LED SMD 0603 Green")
		(tags "LED SMD 0603 Green")
		(property "Reference" "D2"
			(at -0.75 1.58 0)
			(layer "F.SilkS")
			(effects
				(font
					(size 0.7 0.7)
					(thickness 0.15)
				)
				(justify left bottom)
			)
		)
		(property "Value" "LED_G_0603_LTST-C190GKT"
			(at -0.001 1.599 0)
			(layer "F.Fab")
			(effects
				(font
					(size 0.7 0.7)
					(thickness 0.15)
				)
				(justify left bottom)
			)
		)
		(property "Datasheet" "https://media.digikey.com/pdf/Data%20Sheets/Lite-On%20PDFs/LTST-C190GKT.pdf"
			(at 0 0 0)
			(layer "F.Fab")
			(hide yes)
			(effects
				(font
					(size 1.27 1.27)
					(thickness 0.15)
				)
			)
		)
		(property "Description" "LED, Green, SMD, 0603, 20 mA, 2.1 V, 569 nm"
			(at 0 0 0)
			(layer "F.Fab")
			(hide yes)
			(effects
				(font
					(size 1.27 1.27)
					(thickness 0.15)
				)
			)
		)
		(property "MPN" "LTST-C190GKT"
			(at 0 0 0)
			(unlocked yes)
			(layer "F.Fab")
			(hide yes)
			(effects
				(font
					(size 1 1)
					(thickness 0.15)
				)
			)
		)
		(property "Manufacturer" "Lite-On"
			(at 0 0 0)
			(unlocked yes)
			(layer "F.Fab")
			(hide yes)
			(effects
				(font
					(size 1 1)
					(thickness 0.15)
				)
			)
		)
		(property "Color" "Green"
			(at 0 0 0)
			(unlocked yes)
			(layer "F.Fab")
			(hide yes)
			(effects
				(font
					(size 1 1)
					(thickness 0.15)
				)
			)
		)
		(property "Author" "Antmicro"
			(at 0 0 0)
			(unlocked yes)
			(layer "F.Fab")
			(hide yes)
			(effects
				(font
					(size 1 1)
					(thickness 0.15)
				)
			)
		)
		(property "License" "Apache-2.0"
			(at 0 0 0)
			(unlocked yes)
			(layer "F.Fab")
			(hide yes)
			(effects
				(font
					(size 1 1)
					(thickness 0.15)
				)
			)
		)
		(sheetname "/Power/")
		(sheetfile "power.kicad_sch")
		(attr smd)
		(fp_line
			(start -1.18 -0.319)
			(end -1.18 0.321)
			(stroke
				(width 0.15)
				(type solid)
			)
			(layer "F.SilkS")
		)
		(fp_line
			(start -0.094672 0.001008)
			(end -0.24 0.001008)
			(stroke
				(width 0.1)
				(type solid)
			)
			(layer "F.SilkS")
		)
		(fp_line
			(start -0.094672 0.001008)
			(end 0.105328 -0.198992)
			(stroke
				(width 0.1)
				(type solid)
			)
			(layer "F.SilkS")
		)
		(fp_line
			(start -0.094672 0.201008)
			(end -0.094672 -0.198992)
			(stroke
				(width 0.1)
				(type solid)
			)
			(layer "F.SilkS")
		)
		(fp_line
			(start 0.105328 0.001008)
			(end 0.24 0.001)
			(stroke
				(width 0.1)
				(type solid)
			)
			(layer "F.SilkS")
		)
		(fp_line
			(start 0.105328 0.201008)
			(end -0.094672 0.001008)
			(stroke
				(width 0.1)
				(type solid)
			)
			(layer "F.SilkS")
		)
		(fp_line
			(start 0.105328 0.201008)
			(end 0.105328 -0.198992)
			(stroke
				(width 0.1)
				(type solid)
			)
			(layer "F.SilkS")
		)
		(fp_line
			(start 0.22 -0.35)
			(end -0.22 -0.35)
			(stroke
				(width 0.15)
				(type solid)
			)
			(layer "F.SilkS")
		)
		(fp_line
			(start 0.22 0.35)
			(end -0.22 0.35)
			(stroke
				(width 0.15)
				(type solid)
			)
			(layer "F.SilkS")
		)
		(fp_rect
			(start 1.25 0.65)
			(end -1.25 -0.65)
			(stroke
				(width 0.05)
				(type solid)
			)
			(fill no)
			(layer "F.CrtYd")
		)
		(fp_line
			(start -0.199 -0.202)
			(end -0.199 0.1)
			(stroke
				(width 0.15)
				(type solid)
			)
			(layer "F.Fab")
		)
		(fp_line
			(start -0.199 0)
			(end -0.597 0)
			(stroke
				(width 0.15)
				(type solid)
			)
			(layer "F.Fab")
		)
		(fp_line
			(start -0.199 0.2)
			(end -0.199 0.1)
			(stroke
				(width 0.15)
				(type solid)
			)
			(layer "F.Fab")
		)
		(fp_line
			(start -0.101 0)
			(end 0.201 0.2)
			(stroke
				(width 0.15)
				(type solid)
			)
			(layer "F.Fab")
		)
		(fp_line
			(start 0.201 -0.202)
			(end -0.101 0)
			(stroke
				(width 0.15)
				(type solid)
			)
			(layer "F.Fab")
		)
		(fp_line
			(start 0.201 0)
			(end 0.201 -0.202)
			(stroke
				(width 0.15)
				(type solid)
			)
			(layer "F.Fab")
		)
		(fp_line
			(start 0.201 0.2)
			(end 0.201 0)
			(stroke
				(width 0.15)
				(type solid)
			)
			(layer "F.Fab")
		)
		(fp_line
			(start 0.599 0)
			(end 0.201 0)
			(stroke
				(width 0.15)
				(type solid)
			)
			(layer "F.Fab")
		)
		(fp_rect
			(start 0.848 0.4)
			(end -0.85 -0.402)
			(stroke
				(width 0.15)
				(type solid)
			)
			(fill no)
			(layer "F.Fab")
		)
		(fp_text user "${REFERENCE}"
			(at 0 0 0)
			(layer "F.Fab")
			(effects
				(font
					(size 0.7 0.7)
					(thickness 0.15)
				)
				(justify left bottom)
			)
		)
		(fp_text user "License: Apache-2.0"
			(at -1.4224 3.599 0)
			(layer "F.Fab")
			(effects
				(font
					(size 0.7 0.7)
					(thickness 0.15)
				)
				(justify left bottom)
			)
		)
		(fp_text user "Author: Antmicro"
			(at -1.4224 4.799 0)
			(layer "F.Fab")
			(effects
				(font
					(size 0.7 0.7)
					(thickness 0.15)
				)
				(justify left bottom)
			)
		)
		(pad "1" smd roundrect
			(at -0.7 0 180)
			(size 0.8 1)
			(layers "F.Cu" "F.Mask" "F.Paste")
			(roundrect_rratio 0.2)
			(net 90 "Net-(D2-C)")
			(pinfunction "C")
			(pintype "passive")
		)
		(pad "2" smd roundrect
			(at 0.7 0 180)
			(size 0.8 1)
			(layers "F.Cu" "F.Mask" "F.Paste")
			(roundrect_rratio 0.2)
			(net 134 "+3V3")
			(pinfunction "A")
			(pintype "passive")
		)
	)
	(footprint "antmicro-footprints:C_0402_1005Metric"
		(layer "F.Cu")
		(at 140.900001 122.152999 180)
		(descr "Capacitor SMD 0402")
		(tags "capacitor SMD 0402")
		(property "Reference" "C35"
			(at -0.999999 -0.647001 180)
			(layer "F.SilkS")
			(effects
				(font
					(size 0.7 0.7)
					(thickness 0.15)
				)
				(justify right top)
			)
		)
		(property "Value" "C_1u_25V_0402"
			(at -1.022927 2.155213 0)
			(layer "F.Fab")
			(effects
				(font
					(size 0.7 0.7)
					(thickness 0.15)
				)
				(justify right top)
			)
		)
		(property "Datasheet" "https://www.murata.com/products/productdetail?partno=GRM155R61E105KE11%23"
			(at 0 0 0)
			(layer "F.Fab")
			(hide yes)
			(effects
				(font
					(size 1.27 1.27)
					(thickness 0.15)
				)
			)
		)
		(property "Description" "SMD Multilayer Ceramic Capacitor, 1 µF, 25 V, 0402 [1005 Metric], ± 10%, X5R, GRM Series"
			(at 0 0 0)
			(layer "F.Fab")
			(hide yes)
			(effects
				(font
					(size 1.27 1.27)
					(thickness 0.15)
				)
			)
		)
		(property "MPN" "GRM155R61E105KE11J"
			(at 0 0 180)
			(unlocked yes)
			(layer "F.Fab")
			(hide yes)
			(effects
				(font
					(size 1 1)
					(thickness 0.15)
				)
			)
		)
		(property "Manufacturer" "Murata"
			(at 0 0 180)
			(unlocked yes)
			(layer "F.Fab")
			(hide yes)
			(effects
				(font
					(size 1 1)
					(thickness 0.15)
				)
			)
		)
		(property "License" "Apache-2.0"
			(at 0 0 180)
			(unlocked yes)
			(layer "F.Fab")
			(hide yes)
			(effects
				(font
					(size 1 1)
					(thickness 0.15)
				)
			)
		)
		(property "Author" "Antmicro"
			(at 0 0 180)
			(unlocked yes)
			(layer "F.Fab")
			(hide yes)
			(effects
				(font
					(size 1 1)
					(thickness 0.15)
				)
			)
		)
		(property "Val" "1u"
			(at 0 0 180)
			(unlocked yes)
			(layer "F.Fab")
			(hide yes)
			(effects
				(font
					(size 1 1)
					(thickness 0.15)
				)
			)
		)
		(property "Voltage" "25V"
			(at 0 0 180)
			(unlocked yes)
			(layer "F.Fab")
			(hide yes)
			(effects
				(font
					(size 1 1)
					(thickness 0.15)
				)
			)
		)
		(property "Dielectric" "X5R"
			(at 0 0 180)
			(unlocked yes)
			(layer "F.Fab")
			(hide yes)
			(effects
				(font
					(size 1 1)
					(thickness 0.15)
				)
			)
		)
		(sheetname "/Power/Ideal-diode-1/")
		(sheetfile "ideal-diode.kicad_sch")
		(attr smd)
		(fp_rect
			(start -0.925 -0.47)
			(end 0.925 0.47)
			(stroke
				(width 0.05)
				(type default)
			)
			(fill no)
			(layer "F.CrtYd")
		)
		(fp_line
			(start 0.504 0.248)
			(end -0.494 0.248)
			(stroke
				(width 0.15)
				(type solid)
			)
			(layer "F.Fab")
		)
		(fp_line
			(start 0.504 -0.25)
			(end 0.504 0.248)
			(stroke
				(width 0.15)
				(type solid)
			)
			(layer "F.Fab")
		)
		(fp_line
			(start -0.494 0.248)
			(end -0.494 -0.25)
			(stroke
				(width 0.15)
				(type solid)
			)
			(layer "F.Fab")
		)
		(fp_line
			(start -0.494 -0.25)
			(end 0.504 -0.25)
			(stroke
				(width 0.15)
				(type solid)
			)
			(layer "F.Fab")
		)
		(fp_text user "License: Apache-2.0"
			(at -0.939 5.799 0)
			(layer "F.Fab")
			(effects
				(font
					(size 0.7 0.7)
					(thickness 0.15)
				)
				(justify right top)
			)
		)
		(fp_text user "Author: Antmicro"
			(at -0.939 3.399 0)
			(layer "F.Fab")
			(effects
				(font
					(size 0.7 0.7)
					(thickness 0.15)
				)
				(justify right top)
			)
		)
		(fp_text user "${REFERENCE}"
			(at 0 0 0)
			(layer "F.Fab")
			(effects
				(font
					(size 0.7 0.7)
					(thickness 0.15)
				)
				(justify right top)
			)
		)
		(pad "1" smd roundrect
			(at -0.48 0 180)
			(size 0.59 0.64)
			(layers "F.Cu" "F.Mask" "F.Paste")
			(roundrect_rratio 0.25)
			(net 66 "GND")
			(pintype "passive")
		)
		(pad "2" smd roundrect
			(at 0.48 0 180)
			(size 0.59 0.64)
			(layers "F.Cu" "F.Mask" "F.Paste")
			(roundrect_rratio 0.25)
			(net 87 "+12V")
			(pintype "passive")
		)
	)
	(footprint "antmicro-footprints:R_0402_1005Metric"
		(layer "F.Cu")
		(at 119.55 45.75 -90)
		(descr "Resistor SMD 0402")
		(tags "resistor SMD 0402")
		(property "Reference" "R46"
			(at -3.15 0.35 270)
			(layer "F.SilkS")
			(effects
				(font
					(size 0.7 0.7)
					(thickness 0.15)
				)
				(justify right top)
			)
		)
		(property "Value" "R_0R_0402"
			(at -1.011843 1.772046 90)
			(layer "F.Fab")
			(effects
				(font
					(size 0.7 0.7)
					(thickness 0.15)
				)
				(justify right top)
			)
		)
		(property "Datasheet" "https://industrial.panasonic.com/cdbs/www-data/pdf/RDA0000/AOA0000C301.pdf"
			(at 0 0 90)
			(layer "F.Fab")
			(hide yes)
			(effects
				(font
					(size 1.27 1.27)
					(thickness 0.15)
				)
			)
		)
		(property "Description" "SMD Chip Resistor, Jumper, 0 ohm, 100 mW, 0402 [1005 Metric], Thick Film, General Purpose"
			(at 0 0 90)
			(layer "F.Fab")
			(hide yes)
			(effects
				(font
					(size 1.27 1.27)
					(thickness 0.15)
				)
			)
		)
		(property "MPN" "ERJ2GE0R00X"
			(at 0 0 270)
			(unlocked yes)
			(layer "F.Fab")
			(hide yes)
			(effects
				(font
					(size 1 1)
					(thickness 0.15)
				)
			)
		)
		(property "Manufacturer" "Panasonic"
			(at 0 0 270)
			(unlocked yes)
			(layer "F.Fab")
			(hide yes)
			(effects
				(font
					(size 1 1)
					(thickness 0.15)
				)
			)
		)
		(property "License" "Apache-2.0"
			(at 0 0 270)
			(unlocked yes)
			(layer "F.Fab")
			(hide yes)
			(effects
				(font
					(size 1 1)
					(thickness 0.15)
				)
			)
		)
		(property "Author" "Antmicro"
			(at 0 0 270)
			(unlocked yes)
			(layer "F.Fab")
			(hide yes)
			(effects
				(font
					(size 1 1)
					(thickness 0.15)
				)
			)
		)
		(property "Val" "0R"
			(at 0 0 270)
			(unlocked yes)
			(layer "F.Fab")
			(hide yes)
			(effects
				(font
					(size 1 1)
					(thickness 0.15)
				)
			)
		)
		(property "Tolerance" ""
			(at 0 0 270)
			(unlocked yes)
			(layer "F.Fab")
			(hide yes)
			(effects
				(font
					(size 1 1)
					(thickness 0.15)
				)
			)
		)
		(property "Current" "1A"
			(at 0 0 270)
			(unlocked yes)
			(layer "F.Fab")
			(hide yes)
			(effects
				(font
					(size 1 1)
					(thickness 0.15)
				)
			)
		)
		(sheetname "/OCuLink/")
		(sheetfile "oculink.kicad_sch")
		(attr smd)
		(fp_rect
			(start -0.925 -0.47)
			(end 0.925 0.47)
			(stroke
				(width 0.05)
				(type default)
			)
			(fill no)
			(layer "F.CrtYd")
		)
		(fp_rect
			(start -0.5 -0.25)
			(end 0.5 0.25)
			(stroke
				(width 0.15)
				(type solid)
			)
			(fill no)
			(layer "F.Fab")
		)
		(fp_text user "${REFERENCE}"
			(at 0 0 90)
			(layer "F.Fab")
			(effects
				(font
					(size 0.7 0.7)
					(thickness 0.15)
				)
				(justify right top)
			)
		)
		(fp_text user "License: Apache-2.0"
			(at -0.949999 5.169 90)
			(layer "F.Fab")
			(effects
				(font
					(size 0.7 0.7)
					(thickness 0.15)
				)
				(justify right top)
			)
		)
		(fp_text user "Author: Antmicro"
			(at -0.95 4.169 90)
			(layer "F.Fab")
			(effects
				(font
					(size 0.7 0.7)
					(thickness 0.15)
				)
				(justify right top)
			)
		)
		(pad "1" smd roundrect
			(at -0.48 0 270)
			(size 0.59 0.64)
			(layers "F.Cu" "F.Mask" "F.Paste")
			(roundrect_rratio 0.25)
			(net 170 "/OCuLink/PCIe_{REF0}_R.CK+")
			(pintype "passive")
		)
		(pad "2" smd roundrect
			(at 0.48 0 270)
			(size 0.59 0.64)
			(layers "F.Cu" "F.Mask" "F.Paste")
			(roundrect_rratio 0.25)
			(net 96 "/OCuLink/PCIe_{REF0}.CK+")
			(pintype "passive")
		)
	)
)
